# SCM (Grand Teton) — schematic netlist excerpt (pin names and nets, part order shuffled) for the footprints in the layout excerpt that follows; sources: Cadence DE-HDL packaged netlist, KiCad conversion of 12092022_DA0F0TMDCD0_F0T_Management_Board_D_brd_V3_OCP.brd

PC225  Q_CAP  0.1UF 25V 10% X7R  pkg 0402  page 52 : A = P3V3_AUX ; B = GND
R88  Q_RES  150 1% CHIP  pkg 0402LF  page 23 : A = V_DACG_IO ; B = GND

(kicad_pcb
	(version 20260206)
	(generator "pcbnew")
	(generator_version "10.0")
	(general
		(thickness 1.6)
		(legacy_teardrops no)
	)
	(paper "A4")
	(title_block
		(title "12092022_DA0F0TMDCD0_F0T_Management_Board_D_brd_V3_OCP.brd")
		(comment 1 "Grand Teton / footprints 249-250 of 1440")
	)
	(layers
		(0 "F.Cu" signal "TOP")
		(4 "In1.Cu" signal "GND")
		(6 "In2.Cu" signal "IN1")
		(8 "In3.Cu" signal "GND1")
		(10 "In4.Cu" signal "IN2")
		(12 "In5.Cu" signal "VCC")
		(14 "In6.Cu" signal "VCC1")
		(16 "In7.Cu" signal "IN3")
		(18 "In8.Cu" signal "GND2")
		(20 "In9.Cu" signal "IN4")
		(22 "In10.Cu" signal "GND3")
		(2 "B.Cu" signal "BOTTOM")
		(9 "F.Adhes" user "F.Adhesive")
		(11 "B.Adhes" user "B.Adhesive")
		(13 "F.Paste" user "Package Geometry/Pastemask Top")
		(15 "B.Paste" user "Package Geometry/Pastemask Bottom")
		(5 "F.SilkS" user "Ref Des/Silkscreen Top")
		(7 "B.SilkS" user "Ref Des/Silkscreen Bottom")
		(1 "F.Mask" user "Board Geometry/Soldermask Top")
		(3 "B.Mask" user "Board Geometry/Soldermask Bottom")
		(17 "Dwgs.User" user "User.Drawings")
		(19 "Cmts.User" user "User.Comments")
		(21 "Eco1.User" user "User.Eco1")
		(23 "Eco2.User" user "User.Eco2")
		(25 "Edge.Cuts" user "Board Geometry/Outline")
		(27 "Margin" user)
		(31 "F.CrtYd" user "Package Geometry/Place Bound Top")
		(29 "B.CrtYd" user "Package Geometry/Place Bound Bottom")
		(35 "F.Fab" user "Ref Des/Assembly Top")
		(33 "B.Fab" user "Ref Des/Assembly Bottom")
	)
	(footprint ""
		(layer "F.Cu")
		(at 12.684252 -78.053184 90)
		(property "Reference" "PC225"
			(at 0 0 90)
			(layer "F.SilkS")
			(hide yes)
			(effects
				(font
					(size 1.27 1.27)
				)
			)
		)
		(property "Value" ""
			(at 0 0 90)
			(layer "F.Fab")
			(effects
				(font
					(size 1.27 1.27)
				)
			)
		)
		(duplicate_pad_numbers_are_jumpers no)
		(fp_line
			(start 0.7874 -0.4064)
			(end 0.7874 0.4064)
			(stroke
				(width 0.1524)
				(type default)
			)
			(layer "F.SilkS")
		)
		(fp_line
			(start -0.7874 -0.4064)
			(end 0.7874 -0.4064)
			(stroke
				(width 0.1524)
				(type default)
			)
			(layer "F.SilkS")
		)
		(fp_line
			(start 0.7874 0.4064)
			(end -0.7874 0.4064)
			(stroke
				(width 0.1524)
				(type default)
			)
			(layer "F.SilkS")
		)
		(fp_line
			(start -0.7874 0.4064)
			(end -0.7874 -0.4064)
			(stroke
				(width 0.1524)
				(type default)
			)
			(layer "F.SilkS")
		)
		(fp_line
			(start -0.12065 -0.305054)
			(end -0.12065 -0.2794)
			(stroke
				(width 0.1)
				(type default)
			)
			(layer "F.Fab")
		)
		(fp_line
			(start -0.67945 -0.305054)
			(end -0.12065 -0.305054)
			(stroke
				(width 0.1)
				(type default)
			)
			(layer "F.Fab")
		)
		(fp_line
			(start 0.67945 -0.3048)
			(end 0.67945 0.3048)
			(stroke
				(width 0.1)
				(type default)
			)
			(layer "F.Fab")
		)
		(fp_line
			(start 0.12065 -0.3048)
			(end 0.67945 -0.3048)
			(stroke
				(width 0.1)
				(type default)
			)
			(layer "F.Fab")
		)
		(fp_line
			(start 0.12065 -0.2794)
			(end 0.12065 -0.3048)
			(stroke
				(width 0.1)
				(type default)
			)
			(layer "F.Fab")
		)
		(fp_line
			(start -0.12065 -0.2794)
			(end 0.12065 -0.2794)
			(stroke
				(width 0.1)
				(type default)
			)
			(layer "F.Fab")
		)
		(fp_line
			(start 0.120396 0.2794)
			(end -0.12065 0.2794)
			(stroke
				(width 0.1)
				(type default)
			)
			(layer "F.Fab")
		)
		(fp_line
			(start -0.12065 0.2794)
			(end -0.12065 0.3048)
			(stroke
				(width 0.1)
				(type default)
			)
			(layer "F.Fab")
		)
		(fp_line
			(start 0.67945 0.3048)
			(end 0.120396 0.3048)
			(stroke
				(width 0.1)
				(type default)
			)
			(layer "F.Fab")
		)
		(fp_line
			(start 0.120396 0.3048)
			(end 0.120396 0.2794)
			(stroke
				(width 0.1)
				(type default)
			)
			(layer "F.Fab")
		)
		(fp_line
			(start -0.12065 0.3048)
			(end -0.67945 0.3048)
			(stroke
				(width 0.1)
				(type default)
			)
			(layer "F.Fab")
		)
		(fp_line
			(start -0.67945 0.3048)
			(end -0.67945 -0.305054)
			(stroke
				(width 0.1)
				(type default)
			)
			(layer "F.Fab")
		)
		(pad "1" smd circle
			(at -0.40005 0 90)
			(size 0 0)
			(layers "F.Cu" "F.Mask" "F.Paste")
			(net "P3V3_AUX")
		)
		(pad "2" smd circle
			(at 0.40005 0 90)
			(size 0 0)
			(layers "F.Cu" "F.Mask" "F.Paste")
			(net "GND")
		)
	)
	(footprint ""
		(layer "F.Cu")
		(at 29.464 -31.369 180)
		(property "Reference" "R88"
			(at 0 0 180)
			(layer "F.SilkS")
			(hide yes)
			(effects
				(font
					(size 1.27 1.27)
				)
			)
		)
		(property "Value" ""
			(at 0 0 180)
			(layer "F.Fab")
			(effects
				(font
					(size 1.27 1.27)
				)
			)
		)
		(duplicate_pad_numbers_are_jumpers no)
		(fp_line
			(start 0.7874 0.4064)
			(end -0.7874 0.4064)
			(stroke
				(width 0.1524)
				(type default)
			)
			(layer "F.SilkS")
		)
		(fp_line
			(start 0.7874 -0.4064)
			(end 0.7874 0.4064)
			(stroke
				(width 0.1524)
				(type default)
			)
			(layer "F.SilkS")
		)
		(fp_line
			(start -0.7874 0.4064)
			(end -0.7874 -0.4064)
			(stroke
				(width 0.1524)
				(type default)
			)
			(layer "F.SilkS")
		)
		(fp_line
			(start -0.7874 -0.4064)
			(end 0.7874 -0.4064)
			(stroke
				(width 0.1524)
				(type default)
			)
			(layer "F.SilkS")
		)
		(fp_line
			(start 0.67945 0.3048)
			(end 0.120396 0.3048)
			(stroke
				(width 0.1)
				(type default)
			)
			(layer "F.Fab")
		)
		(fp_line
			(start 0.67945 -0.3048)
			(end 0.67945 0.3048)
			(stroke
				(width 0.1)
				(type default)
			)
			(layer "F.Fab")
		)
		(fp_line
			(start 0.12065 -0.2794)
			(end 0.12065 -0.3048)
			(stroke
				(width 0.1)
				(type default)
			)
			(layer "F.Fab")
		)
		(fp_line
			(start 0.12065 -0.3048)
			(end 0.67945 -0.3048)
			(stroke
				(width 0.1)
				(type default)
			)
			(layer "F.Fab")
		)
		(fp_line
			(start 0.120396 0.3048)
			(end 0.120396 0.2794)
			(stroke
				(width 0.1)
				(type default)
			)
			(layer "F.Fab")
		)
		(fp_line
			(start 0.120396 0.2794)
			(end -0.12065 0.2794)
			(stroke
				(width 0.1)
				(type default)
			)
			(layer "F.Fab")
		)
		(fp_line
			(start -0.12065 0.3048)
			(end -0.67945 0.3048)
			(stroke
				(width 0.1)
				(type default)
			)
			(layer "F.Fab")
		)
		(fp_line
			(start -0.12065 0.2794)
			(end -0.12065 0.3048)
			(stroke
				(width 0.1)
				(type default)
			)
			(layer "F.Fab")
		)
		(fp_line
			(start -0.12065 -0.2794)
			(end 0.12065 -0.2794)
			(stroke
				(width 0.1)
				(type default)
			)
			(layer "F.Fab")
		)
		(fp_line
			(start -0.12065 -0.305054)
			(end -0.12065 -0.2794)
			(stroke
				(width 0.1)
				(type default)
			)
			(layer "F.Fab")
		)
		(fp_line
			(start -0.67945 0.3048)
			(end -0.67945 -0.305054)
			(stroke
				(width 0.1)
				(type default)
			)
			(layer "F.Fab")
		)
		(fp_line
			(start -0.67945 -0.305054)
			(end -0.12065 -0.305054)
			(stroke
				(width 0.1)
				(type default)
			)
			(layer "F.Fab")
		)
		(pad "1" smd circle
			(at -0.40005 0 180)
			(size 0 0)
			(layers "F.Cu" "F.Mask" "F.Paste")
			(net "V_DACG_IO")
		)
		(pad "2" smd circle
			(at 0.40005 0 180)
			(size 0 0)
			(layers "F.Cu" "F.Mask" "F.Paste")
			(net "GND")
		)
	)
)
